# T6G (Grand Teton) — schematic netlist excerpt (pin names and nets, part order shuffled) for the footprints in the layout excerpt that follows; sources: Cadence DE-HDL packaged netlist, KiCad conversion of 04192023_DAF0TMB3IC0_F0TG_MB_C_brd_V02_OCP.brd

R4169  Q_RES  100K 1% CHIP  pkg 0402LF  page 124 : A = P3V3_AUX ; B = GPU_3V3IO_RSVD3_ISO
R63  Q_RES  33 5% CHIP  pkg 0402LF  page 80 : A = SCM_SYS_PWROK_R ; B = SCM_SYS_PWROK
R843  Q_RES  4.7K 5% EMPTY  pkg 0201LF  page 185 : A = P1V8_AUX ; B = RT_ROM_SMB_MUX_ADDR1

(kicad_pcb
	(version 20260206)
	(generator "pcbnew")
	(generator_version "10.0")
	(general
		(thickness 1.6)
		(legacy_teardrops no)
	)
	(paper "A4")
	(title_block
		(title "04192023_DAF0TMB3IC0_F0TG_MB_C_brd_V02_OCP.brd")
		(comment 1 "Grand Teton / footprints 8138-8140 of 8354")
	)
	(layers
		(0 "F.Cu" signal "TOP")
		(4 "In1.Cu" signal "GND")
		(6 "In2.Cu" signal "IN1")
		(8 "In3.Cu" signal "GND1")
		(10 "In4.Cu" signal "IN2")
		(12 "In5.Cu" signal "GND2")
		(14 "In6.Cu" signal "IN3")
		(16 "In7.Cu" signal "GND3")
		(18 "In8.Cu" signal "VCC")
		(20 "In9.Cu" signal "VCC1")
		(22 "In10.Cu" signal "GND4")
		(24 "In11.Cu" signal "IN4")
		(26 "In12.Cu" signal "GND5")
		(28 "In13.Cu" signal "IN5")
		(30 "In14.Cu" signal "GND6")
		(32 "In15.Cu" signal "IN6")
		(34 "In16.Cu" signal "GND7")
		(2 "B.Cu" signal "BOTTOM")
		(9 "F.Adhes" user "F.Adhesive")
		(11 "B.Adhes" user "B.Adhesive")
		(13 "F.Paste" user "Package Geometry/Pastemask Top")
		(15 "B.Paste" user "Package Geometry/Pastemask Bottom")
		(5 "F.SilkS" user "Ref Des/Silkscreen Top")
		(7 "B.SilkS" user "Ref Des/Silkscreen Bottom")
		(1 "F.Mask" user "Board Geometry/Soldermask Top")
		(3 "B.Mask" user "Board Geometry/Soldermask Bottom")
		(17 "Dwgs.User" user "User.Drawings")
		(19 "Cmts.User" user "User.Comments")
		(21 "Eco1.User" user "User.Eco1")
		(23 "Eco2.User" user "User.Eco2")
		(25 "Edge.Cuts" user "Board Geometry/Outline")
		(27 "Margin" user)
		(31 "F.CrtYd" user "Package Geometry/Place Bound Top")
		(29 "B.CrtYd" user "Package Geometry/Place Bound Bottom")
		(35 "F.Fab" user "Ref Des/Assembly Top")
		(33 "B.Fab" user "Ref Des/Assembly Bottom")
	)
	(footprint ""
		(layer "B.Cu")
		(at 167.132 -119.344948 180)
		(property "Reference" "R63"
			(at 0 0 0)
			(layer "B.SilkS")
			(hide yes)
			(effects
				(font
					(size 1.27 1.27)
				)
				(justify mirror)
			)
		)
		(property "Value" ""
			(at 0 0 0)
			(layer "B.Fab")
			(effects
				(font
					(size 1.27 1.27)
				)
				(justify mirror)
			)
		)
		(duplicate_pad_numbers_are_jumpers no)
		(fp_line
			(start 0.7874 0.4064)
			(end 0.7874 -0.4064)
			(stroke
				(width 0.1524)
				(type default)
			)
			(layer "B.SilkS")
		)
		(fp_line
			(start 0.7874 -0.4064)
			(end -0.7874 -0.4064)
			(stroke
				(width 0.1524)
				(type default)
			)
			(layer "B.SilkS")
		)
		(fp_line
			(start -0.7874 0.4064)
			(end 0.7874 0.4064)
			(stroke
				(width 0.1524)
				(type default)
			)
			(layer "B.SilkS")
		)
		(fp_line
			(start -0.7874 -0.4064)
			(end -0.7874 0.4064)
			(stroke
				(width 0.1524)
				(type default)
			)
			(layer "B.SilkS")
		)
		(fp_line
			(start 0.67945 0.3048)
			(end 0.67945 -0.305054)
			(stroke
				(width 0.1)
				(type default)
			)
			(layer "B.Fab")
		)
		(fp_line
			(start 0.67945 -0.305054)
			(end 0.12065 -0.305054)
			(stroke
				(width 0.1)
				(type default)
			)
			(layer "B.Fab")
		)
		(fp_line
			(start 0.12065 0.3048)
			(end 0.67945 0.3048)
			(stroke
				(width 0.1)
				(type default)
			)
			(layer "B.Fab")
		)
		(fp_line
			(start 0.12065 0.2794)
			(end 0.12065 0.3048)
			(stroke
				(width 0.1)
				(type default)
			)
			(layer "B.Fab")
		)
		(fp_line
			(start 0.12065 -0.2794)
			(end -0.12065 -0.2794)
			(stroke
				(width 0.1)
				(type default)
			)
			(layer "B.Fab")
		)
		(fp_line
			(start 0.12065 -0.305054)
			(end 0.12065 -0.2794)
			(stroke
				(width 0.1)
				(type default)
			)
			(layer "B.Fab")
		)
		(fp_line
			(start -0.120396 0.3048)
			(end -0.120396 0.2794)
			(stroke
				(width 0.1)
				(type default)
			)
			(layer "B.Fab")
		)
		(fp_line
			(start -0.120396 0.2794)
			(end 0.12065 0.2794)
			(stroke
				(width 0.1)
				(type default)
			)
			(layer "B.Fab")
		)
		(fp_line
			(start -0.12065 -0.2794)
			(end -0.12065 -0.3048)
			(stroke
				(width 0.1)
				(type default)
			)
			(layer "B.Fab")
		)
		(fp_line
			(start -0.12065 -0.3048)
			(end -0.67945 -0.3048)
			(stroke
				(width 0.1)
				(type default)
			)
			(layer "B.Fab")
		)
		(fp_line
			(start -0.67945 0.3048)
			(end -0.120396 0.3048)
			(stroke
				(width 0.1)
				(type default)
			)
			(layer "B.Fab")
		)
		(fp_line
			(start -0.67945 -0.3048)
			(end -0.67945 0.3048)
			(stroke
				(width 0.1)
				(type default)
			)
			(layer "B.Fab")
		)
		(pad "1" smd circle
			(at 0.40005 0)
			(size 0 0)
			(layers "B.Cu" "B.Mask" "B.Paste")
			(net "SCM_SYS_PWROK_R")
		)
		(pad "2" smd circle
			(at -0.40005 0)
			(size 0 0)
			(layers "B.Cu" "B.Mask" "B.Paste")
			(net "SCM_SYS_PWROK")
		)
	)
	(footprint ""
		(layer "B.Cu")
		(at 241.140488 -331.597 180)
		(property "Reference" "R843"
			(at 0 0 0)
			(layer "B.SilkS")
			(hide yes)
			(effects
				(font
					(size 1.27 1.27)
				)
				(justify mirror)
			)
		)
		(property "Value" ""
			(at 0 0 0)
			(layer "B.Fab")
			(effects
				(font
					(size 1.27 1.27)
				)
				(justify mirror)
			)
		)
		(duplicate_pad_numbers_are_jumpers no)
		(fp_line
			(start 0.32512 0.175006)
			(end 0.32512 -0.175006)
			(stroke
				(width 0.1)
				(type default)
			)
			(layer "B.Fab")
		)
		(fp_line
			(start 0.32512 -0.175006)
			(end -0.32512 -0.175006)
			(stroke
				(width 0.1)
				(type default)
			)
			(layer "B.Fab")
		)
		(fp_line
			(start -0.32512 0.175006)
			(end 0.32512 0.175006)
			(stroke
				(width 0.1)
				(type default)
			)
			(layer "B.Fab")
		)
		(fp_line
			(start -0.32512 -0.175006)
			(end -0.32512 0.175006)
			(stroke
				(width 0.1)
				(type default)
			)
			(layer "B.Fab")
		)
		(pad "1" smd rect
			(at 0.2667 0)
			(size 0.3048 0.381)
			(layers "B.Cu" "B.Mask" "B.Paste")
			(net "P1V8_AUX")
		)
		(pad "2" smd rect
			(at -0.2667 0 180)
			(size 0.3048 0.381)
			(layers "B.Cu" "B.Mask" "B.Paste")
			(net "RT_ROM_SMB_MUX_ADDR1")
		)
	)
	(footprint ""
		(layer "B.Cu")
		(at 428.087282 -438.192672 90)
		(property "Reference" "R4169"
			(at 0 0 90)
			(layer "B.SilkS")
			(hide yes)
			(effects
				(font
					(size 1.27 1.27)
				)
				(justify mirror)
			)
		)
		(property "Value" ""
			(at 0 0 90)
			(layer "B.Fab")
			(effects
				(font
					(size 1.27 1.27)
				)
				(justify mirror)
			)
		)
		(duplicate_pad_numbers_are_jumpers no)
		(fp_line
			(start 0.7874 -0.4064)
			(end -0.7874 -0.4064)
			(stroke
				(width 0.1524)
				(type default)
			)
			(layer "B.SilkS")
		)
		(fp_line
			(start -0.7874 -0.4064)
			(end -0.7874 0.4064)
			(stroke
				(width 0.1524)
				(type default)
			)
			(layer "B.SilkS")
		)
		(fp_line
			(start 0.7874 0.4064)
			(end 0.7874 -0.4064)
			(stroke
				(width 0.1524)
				(type default)
			)
			(layer "B.SilkS")
		)
		(fp_line
			(start -0.7874 0.4064)
			(end 0.7874 0.4064)
			(stroke
				(width 0.1524)
				(type default)
			)
			(layer "B.SilkS")
		)
		(fp_line
			(start 0.67945 -0.305054)
			(end 0.12065 -0.305054)
			(stroke
				(width 0.1)
				(type default)
			)
			(layer "B.Fab")
		)
		(fp_line
			(start 0.12065 -0.305054)
			(end 0.12065 -0.2794)
			(stroke
				(width 0.1)
				(type default)
			)
			(layer "B.Fab")
		)
		(fp_line
			(start -0.12065 -0.3048)
			(end -0.67945 -0.3048)
			(stroke
				(width 0.1)
				(type default)
			)
			(layer "B.Fab")
		)
		(fp_line
			(start -0.67945 -0.3048)
			(end -0.67945 0.3048)
			(stroke
				(width 0.1)
				(type default)
			)
			(layer "B.Fab")
		)
		(fp_line
			(start 0.12065 -0.2794)
			(end -0.12065 -0.2794)
			(stroke
				(width 0.1)
				(type default)
			)
			(layer "B.Fab")
		)
		(fp_line
			(start -0.12065 -0.2794)
			(end -0.12065 -0.3048)
			(stroke
				(width 0.1)
				(type default)
			)
			(layer "B.Fab")
		)
		(fp_line
			(start 0.12065 0.2794)
			(end 0.12065 0.3048)
			(stroke
				(width 0.1)
				(type default)
			)
			(layer "B.Fab")
		)
		(fp_line
			(start -0.120396 0.2794)
			(end 0.12065 0.2794)
			(stroke
				(width 0.1)
				(type default)
			)
			(layer "B.Fab")
		)
		(fp_line
			(start 0.67945 0.3048)
			(end 0.67945 -0.305054)
			(stroke
				(width 0.1)
				(type default)
			)
			(layer "B.Fab")
		)
		(fp_line
			(start 0.12065 0.3048)
			(end 0.67945 0.3048)
			(stroke
				(width 0.1)
				(type default)
			)
			(layer "B.Fab")
		)
		(fp_line
			(start -0.120396 0.3048)
			(end -0.120396 0.2794)
			(stroke
				(width 0.1)
				(type default)
			)
			(layer "B.Fab")
		)
		(fp_line
			(start -0.67945 0.3048)
			(end -0.120396 0.3048)
			(stroke
				(width 0.1)
				(type default)
			)
			(layer "B.Fab")
		)
		(pad "1" smd circle
			(at 0.40005 0 270)
			(size 0 0)
			(layers "B.Cu" "B.Mask" "B.Paste")
			(net "P3V3_AUX")
		)
		(pad "2" smd circle
			(at -0.40005 0 270)
			(size 0 0)
			(layers "B.Cu" "B.Mask" "B.Paste")
			(net "GPU_3V3IO_RSVD3_ISO")
		)
	)
)
